# BASEBOARD_FAB2 (Tioga Pass) — schematic netlist excerpt (pin names and nets, part order shuffled) for the footprints in the layout excerpt that follows; sources: Cadence DE-HDL packaged netlist, KiCad conversion of Wiwynn_Tioga_Pass_MB.brd

J4G2  SCONN288_H44441004  SCONN  pkg PIP  page 45
  \12v\(1)  = P12V_NVDIMM_ABC
  VSS(93)  = GND
  DQ(4)  = M_B_DQ<5>
  VSS(92)  = GND
  DQ(0)  = M_B_DQ<1>
  VSS(91)  = GND
  DQS9P  = M_B_DQS_DP<9>
  DQS9N  = M_B_DQS_DN<9>
  VSS(90)  = GND
  DQ(6)  = M_B_DQ<7>
  VSS(89)  = GND
  DQ(2)  = M_B_DQ<3>
  VSS(88)  = GND
  DQ(12)  = M_B_DQ<13>
  VSS(87)  = GND
  DQ(8)  = M_B_DQ<9>
  VSS(86)  = GND
  DQS10P  = M_B_DQS_DP<10>
  DQS10N  = M_B_DQS_DN<10>
  VSS(85)  = GND
  DQ(14)  = M_B_DQ<15>
  VSS(84)  = GND
  DQ(10)  = M_B_DQ<11>
  VSS(83)  = GND
  DQ(20)  = M_B_DQ<21>
  VSS(82)  = GND
  DQ(16)  = M_B_DQ<17>
  VSS(81)  = GND
  DQS11P  = M_B_DQS_DP<11>
  DQS11N  = M_B_DQS_DN<11>
  VSS(80)  = GND
  DQ(22)  = M_B_DQ<23>
  VSS(79)  = GND
  DQ(18)  = M_B_DQ<19>
  VSS(78)  = GND
  DQ(28)  = M_B_DQ<29>
  VSS(77)  = GND
  DQ(24)  = M_B_DQ<25>
  VSS(76)  = GND
  DQS12P  = M_B_DQS_DP<12>
  DQS12N  = M_B_DQS_DN<12>
  VSS(75)  = GND
  DQ(30)  = M_B_DQ<31>
  VSS(74)  = GND
  DQ(26)  = M_B_DQ<27>
  VSS(73)  = GND
  CB(4)  = M_B_ECC<5>
  VSS(72)  = GND
  CB(0)  = M_B_ECC<1>
  VSS(71)  = GND
  DQS17P  = M_B_DQS_DP<17>
  DQS17N  = M_B_DQS_DN<17>
  VSS(70)  = GND
  CB(6)  = M_B_ECC<7>
  VSS(69)  = GND
  CB(2)  = M_B_ECC<3>
  VSS(68)  = GND
  RESET_N  = M_ABC_RST_N
  VDD(25)  = PVDDQ_ABC
  CKE(0)  = M_B_CKE<0>
  VDD(24)  = PVDDQ_ABC
  ACT_N  = M_B_ACT_N
  BG(0)  = M_B_BG<0>
  VDD(23)  = PVDDQ_ABC
  A12  = M_B_MA<12>
  A9  = M_B_MA<9>
  VDD(22)  = PVDDQ_ABC
  A8  = M_B_MA<8>
  A6  = M_B_MA<6>
  VDD(21)  = PVDDQ_ABC
  A3  = M_B_MA<3>
  A1  = M_B_MA<1>
  VDD(20)  = PVDDQ_ABC
  CK0P  = M_B_CLK_DP<0>
  CK0N  = M_B_CLK_DN<0>
  VDD(19)  = PVDDQ_ABC
  VTT(1)  = PVTT_ABC
  EVENT_N  = FM_DIMM_EVENT_COD_N
  A0  = M_B_MA<0>
  VDD(18)  = PVDDQ_ABC
  BA(0)  = M_B_BA<0>
  A16_RAS_N  = M_B_MA<16>
  VDD(17)  = PVDDQ_ABC
  S0_N  = M_B_CS_N<0>
  VDD(16)  = PVDDQ_ABC
  A15_CAS_N  = M_B_MA<15>
  ODT(0)  = M_B_ODT<0>
  VDD(15)  = PVDDQ_ABC
  S1_N  = M_B_CS_N<1>
  VDD(14)  = PVDDQ_ABC
  ODT(1)  = M_B_ODT<1>
  VDD(13)  = PVDDQ_ABC
  S2_N_C(0)  = M_B_CS_N<2>
  VSS(67)  = GND
  DQ(36)  = M_B_DQ<37>
  VSS(66)  = GND
  DQ(32)  = M_B_DQ<33>
  VSS(65)  = GND
  DQS13P  = M_B_DQS_DP<13>
  DQS13N  = M_B_DQS_DN<13>
  VSS(64)  = GND
  DQ(38)  = M_B_DQ<39>
  VSS(63)  = GND
  DQ(34)  = M_B_DQ<35>
  VSS(62)  = GND
  DQ(44)  = M_B_DQ<45>
  VSS(61)  = GND
  DQ(40)  = M_B_DQ<41>
  VSS(60)  = GND
  DQS14P  = M_B_DQS_DP<14>
  DQS14N  = M_B_DQS_DN<14>
  VSS(59)  = GND
  DQ(46)  = M_B_DQ<47>
  VSS(58)  = GND
  DQ(42)  = M_B_DQ<43>
  VSS(57)  = GND
  DQ(52)  = M_B_DQ<53>
  VSS(56)  = GND
  DQ(48)  = M_B_DQ<49>
  VSS(55)  = GND
  DQS15P  = M_B_DQS_DP<15>
  DQS15N  = M_B_DQS_DN<15>
  VSS(54)  = GND
  DQ(54)  = M_B_DQ<55>
  VSS(53)  = GND
  DQ(50)  = M_B_DQ<51>
  VSS(52)  = GND
  DQ(60)  = M_B_DQ<61>
  VSS(51)  = GND
  DQ(56)  = M_B_DQ<57>
  VSS(50)  = GND
  DQS16P  = M_B_DQS_DP<16>
  DQS16N  = M_B_DQS_DN<16>
  VSS(49)  = GND
  DQ(62)  = M_B_DQ<63>
  VSS(48)  = GND
  DQ(58)  = M_B_DQ<59>
  VSS(47)  = GND
  SA(0)  = GND
  SA(1)  = PVPP_ABC
  SCL  = SMB_DDR_ABC_VPP_SCL
  VPP(4)  = PVPP_ABC
  VPP(3)  = PVPP_ABC
  RFU(2)  = TP_CH_B_DIMM_B0_RFU_2
  \12v\(0)  = P12V_NVDIMM_ABC
  VREFCA  = M_B_VREF
  VSS(46)  = GND
  DQ(5)  = M_B_DQ<4>
  VSS(45)  = GND
  DQ(1)  = M_B_DQ<0>
  VSS(44)  = GND
  DQS0N  = M_B_DQS_DN<0>
  DQS0P  = M_B_DQS_DP<0>
  VSS(43)  = GND
  DQ(7)  = M_B_DQ<6>
  VSS(42)  = GND
  DQ(3)  = M_B_DQ<2>
  VSS(41)  = GND
  DQ(13)  = M_B_DQ<12>
  VSS(40)  = GND
  DQ(9)  = M_B_DQ<8>
  VSS(39)  = GND
  DQS1N  = M_B_DQS_DN<1>
  DQS1P  = M_B_DQS_DP<1>
  VSS(38)  = GND
  DQ(15)  = M_B_DQ<14>
  VSS(37)  = GND
  DQ(11)  = M_B_DQ<10>
  VSS(36)  = GND
  DQ(21)  = M_B_DQ<20>
  VSS(35)  = GND
  DQ(17)  = M_B_DQ<16>
  VSS(34)  = GND
  DQS2N  = M_B_DQS_DN<2>
  DQS2P  = M_B_DQS_DP<2>
  VSS(33)  = GND
  DQ(23)  = M_B_DQ<22>
  VSS(32)  = GND
  DQ(19)  = M_B_DQ<18>
  VSS(31)  = GND
  DQ(29)  = M_B_DQ<28>
  VSS(30)  = GND
  DQ(25)  = M_B_DQ<24>
  VSS(29)  = GND
  DQS3N  = M_B_DQS_DN<3>
  DQS3P  = M_B_DQS_DP<3>
  VSS(28)  = GND
  DQ(31)  = M_B_DQ<30>
  VSS(27)  = GND
  DQ(27)  = M_B_DQ<26>
  VSS(26)  = GND
  CB(5)  = M_B_ECC<4>
  VSS(25)  = GND
  CB(1)  = M_B_ECC<0>
  VSS(24)  = GND
  DQS8N  = M_B_DQS_DN<8>
  DQS8P  = M_B_DQS_DP<8>
  VSS(23)  = GND
  CB(7)  = M_B_ECC<6>
  VSS(22)  = GND
  CB(3)  = M_B_ECC<2>
  VSS(21)  = GND
  CKE(1)  = M_B_CKE<1>
  VDD(12)  = PVDDQ_ABC
  RFU(0)  = TP_CH_B_DIMM_B0_RFU_0
  VDD(11)  = PVDDQ_ABC
  BG(1)  = M_B_BG<1>
  ALERT_N  = M_B_ALERT_N
  VDD(10)  = PVDDQ_ABC
  A11  = M_B_MA<11>
  A7  = M_B_MA<7>
  VDD(9)  = PVDDQ_ABC
  A5  = M_B_MA<5>
  A4  = M_B_MA<4>
  VDD(8)  = PVDDQ_ABC
  A2  = M_B_MA<2>
  VDD(7)  = PVDDQ_ABC
  CK1P  = M_B_CLK_DP<1>
  CK1N  = M_B_CLK_DN<1>
  VDD(6)  = PVDDQ_ABC
  VTT(0)  = PVTT_ABC
  PAR  = M_B_PAR
  VDD(5)  = PVDDQ_ABC
  BA(1)  = M_B_BA<1>
  A10  = M_B_MA<10>
  VDD(4)  = PVDDQ_ABC
  RFU(1)  = TP_CH_B_DIMM_B0_RFU_1
  A14_WE_N  = M_B_MA<14>
  VDD(3)  = PVDDQ_ABC
  SAVE_N_NC  = FM_ADR_COMPLETE_ABC_N
  VDD(2)  = PVDDQ_ABC
  A13  = M_B_MA<13>
  VDD(1)  = PVDDQ_ABC
  A17  = M_B_MA<17>
  C(2)  = M_B_C<2>
  VDD(0)  = PVDDQ_ABC
  S3_N_C(1)  = M_B_CS_N<3>
  SA(2)  = GND
  VSS(20)  = GND
  DQ(37)  = M_B_DQ<36>
  VSS(19)  = GND
  DQ(33)  = M_B_DQ<32>
  VSS(18)  = GND
  DQS4N  = M_B_DQS_DN<4>
  DQS4P  = M_B_DQS_DP<4>
  VSS(17)  = GND
  DQ(39)  = M_B_DQ<38>
  VSS(16)  = GND
  DQ(35)  = M_B_DQ<34>
  VSS(15)  = GND
  DQ(45)  = M_B_DQ<44>
  VSS(14)  = GND
  DQ(41)  = M_B_DQ<40>
  VSS(13)  = GND
  DQS5N  = M_B_DQS_DN<5>
  DQS5P  = M_B_DQS_DP<5>
  VSS(12)  = GND
  DQ(47)  = M_B_DQ<46>
  VSS(11)  = GND
  DQ(43)  = M_B_DQ<42>
  VSS(10)  = GND
  DQ(53)  = M_B_DQ<52>
  VSS(9)  = GND
  DQ(49)  = M_B_DQ<48>
  VSS(8)  = GND
  DQS6N  = M_B_DQS_DN<6>
  DQS6P  = M_B_DQS_DP<6>
  VSS(7)  = GND
  DQ(55)  = M_B_DQ<54>
  VSS(6)  = GND
  DQ(51)  = M_B_DQ<50>
  VSS(5)  = GND
  DQ(61)  = M_B_DQ<60>
  VSS(4)  = GND
  DQ(57)  = M_B_DQ<56>
  VSS(3)  = GND
  DQS7N  = M_B_DQS_DN<7>
  DQS7P  = M_B_DQS_DP<7>
  VSS(2)  = GND
  DQ(63)  = M_B_DQ<62>
  VSS(1)  = GND
  DQ(59)  = M_B_DQ<58>
  VSS(0)  = GND
  VDDSPD  = PVPP_ABC
  SDA  = SMB_DDR_ABC_VPP_SDA
  VPP(1)  = PVPP_ABC
  VPP(0)  = PVPP_ABC
  VPP(2)  = PVPP_ABC

(kicad_pcb
	(version 20260206)
	(generator "pcbnew")
	(generator_version "10.0")
	(general
		(thickness 1.6)
		(legacy_teardrops no)
	)
	(paper "A4")
	(title_block
		(title "Wiwynn_Tioga_Pass_MB.brd")
		(comment 1 "Tioga Pass / footprint 1899 of 4770 (J4G2), pads 52-101 of 291")
	)
	(layers
		(0 "F.Cu" signal "TOP")
		(4 "In1.Cu" signal "L2GND")
		(6 "In2.Cu" signal "L3")
		(8 "In3.Cu" signal "L4GND")
		(10 "In4.Cu" signal "L5")
		(12 "In5.Cu" signal "L6GND")
		(14 "In6.Cu" signal "L7VCC")
		(16 "In7.Cu" signal "L8VCC")
		(18 "In8.Cu" signal "L9GND")
		(20 "In9.Cu" signal "L10")
		(22 "In10.Cu" signal "L11GND")
		(24 "In11.Cu" signal "L12")
		(26 "In12.Cu" signal "L13GND")
		(2 "B.Cu" signal "BOTTOM")
		(9 "F.Adhes" user "F.Adhesive")
		(11 "B.Adhes" user "B.Adhesive")
		(13 "F.Paste" user "Package Geometry/Pastemask Top")
		(15 "B.Paste" user "Package Geometry/Pastemask Bottom")
		(5 "F.SilkS" user "Ref Des/Silkscreen Top")
		(7 "B.SilkS" user "Ref Des/Silkscreen Bottom")
		(1 "F.Mask" user "Board Geometry/Soldermask Top")
		(3 "B.Mask" user "Board Geometry/Soldermask Bottom")
		(17 "Dwgs.User" user "User.Drawings")
		(19 "Cmts.User" user "User.Comments")
		(21 "Eco1.User" user "User.Eco1")
		(23 "Eco2.User" user "User.Eco2")
		(25 "Edge.Cuts" user "Board Geometry/Outline")
		(27 "Margin" user)
		(31 "F.CrtYd" user "Package Geometry/Place Bound Top")
		(29 "B.CrtYd" user "Package Geometry/Place Bound Bottom")
		(35 "F.Fab" user "Ref Des/Assembly Top")
		(33 "B.Fab" user "Ref Des/Assembly Bottom")
	)
	(footprint ""
		(layer "F.Cu")
		(at 194.700398 -5.822442 90)
		(property "Reference" "J4G2"
			(at 6.596888 37.58311 0)
			(unlocked yes)
			(layer "F.SilkS")
			(effects
				(font
					(size 0.7874 0.5842)
					(thickness 0.1524)
				)
				(justify left)
			)
		)
		(property "Value" ""
			(at 0 0 90)
			(layer "F.Fab")
			(effects
				(font
					(size 1.27 1.27)
				)
			)
		)
		(duplicate_pad_numbers_are_jumpers no)
		(pad "49" smd rect
			(at 0 40.80002 90)
			(size 1.8034 0.508)
			(layers "F.Cu" "F.Mask" "F.Paste")
			(net "M_B_ECC<1>")
		)
		(pad "50" smd rect
			(at 0 41.649904 90)
			(size 1.8034 0.508)
			(layers "F.Cu" "F.Mask" "F.Paste")
			(net "GND")
		)
		(pad "51" smd rect
			(at 0 42.500042 90)
			(size 1.8034 0.508)
			(layers "F.Cu" "F.Mask" "F.Paste")
			(net "M_B_DQS_DP<17>")
		)
		(pad "52" smd rect
			(at 0 43.349926 90)
			(size 1.8034 0.508)
			(layers "F.Cu" "F.Mask" "F.Paste")
			(net "M_B_DQS_DN<17>")
		)
		(pad "53" smd rect
			(at 0 44.200064 90)
			(size 1.8034 0.508)
			(layers "F.Cu" "F.Mask" "F.Paste")
			(net "GND")
		)
		(pad "54" smd rect
			(at 0 45.049948 90)
			(size 1.8034 0.508)
			(layers "F.Cu" "F.Mask" "F.Paste")
			(net "M_B_ECC<7>")
		)
		(pad "55" smd rect
			(at 0 45.900086 90)
			(size 1.8034 0.508)
			(layers "F.Cu" "F.Mask" "F.Paste")
			(net "GND")
		)
		(pad "56" smd rect
			(at 0 46.74997 90)
			(size 1.8034 0.508)
			(layers "F.Cu" "F.Mask" "F.Paste")
			(net "M_B_ECC<3>")
		)
		(pad "57" smd rect
			(at 0 47.600108 90)
			(size 1.8034 0.508)
			(layers "F.Cu" "F.Mask" "F.Paste")
			(net "GND")
		)
		(pad "58" smd rect
			(at 0 48.449992 90)
			(size 1.8034 0.508)
			(layers "F.Cu" "F.Mask" "F.Paste")
			(net "M_ABC_RST_N")
		)
		(pad "59" smd rect
			(at 0 49.299876 90)
			(size 1.8034 0.508)
			(layers "F.Cu" "F.Mask" "F.Paste")
			(net "PVDDQ_ABC")
		)
		(pad "60" smd rect
			(at 0 50.150014 90)
			(size 1.8034 0.508)
			(layers "F.Cu" "F.Mask" "F.Paste")
			(net "M_B_CKE<0>")
		)
		(pad "61" smd rect
			(at 0 50.999898 90)
			(size 1.8034 0.508)
			(layers "F.Cu" "F.Mask" "F.Paste")
			(net "PVDDQ_ABC")
		)
		(pad "62" smd rect
			(at 0 51.850036 90)
			(size 1.8034 0.508)
			(layers "F.Cu" "F.Mask" "F.Paste")
			(net "M_B_ACT_N")
		)
		(pad "63" smd rect
			(at 0 52.69992 90)
			(size 1.8034 0.508)
			(layers "F.Cu" "F.Mask" "F.Paste")
			(net "M_B_BG<0>")
		)
		(pad "64" smd rect
			(at 0 53.550058 90)
			(size 1.8034 0.508)
			(layers "F.Cu" "F.Mask" "F.Paste")
			(net "PVDDQ_ABC")
		)
		(pad "65" smd rect
			(at 0 54.399942 90)
			(size 1.8034 0.508)
			(layers "F.Cu" "F.Mask" "F.Paste")
			(net "M_B_MA<12>")
		)
		(pad "66" smd rect
			(at 0 55.25008 90)
			(size 1.8034 0.508)
			(layers "F.Cu" "F.Mask" "F.Paste")
			(net "M_B_MA<9>")
		)
		(pad "67" smd rect
			(at 0 56.099964 90)
			(size 1.8034 0.508)
			(layers "F.Cu" "F.Mask" "F.Paste")
			(net "PVDDQ_ABC")
		)
		(pad "68" smd rect
			(at 0 56.950102 90)
			(size 1.8034 0.508)
			(layers "F.Cu" "F.Mask" "F.Paste")
			(net "M_B_MA<8>")
		)
		(pad "69" smd rect
			(at 0 57.799986 90)
			(size 1.8034 0.508)
			(layers "F.Cu" "F.Mask" "F.Paste")
			(net "M_B_MA<6>")
		)
		(pad "70" smd rect
			(at 0 58.650124 90)
			(size 1.8034 0.508)
			(layers "F.Cu" "F.Mask" "F.Paste")
			(net "PVDDQ_ABC")
		)
		(pad "71" smd rect
			(at 0 59.500008 90)
			(size 1.8034 0.508)
			(layers "F.Cu" "F.Mask" "F.Paste")
			(net "M_B_MA<3>")
		)
		(pad "72" smd rect
			(at 0 60.349892 90)
			(size 1.8034 0.508)
			(layers "F.Cu" "F.Mask" "F.Paste")
			(net "M_B_MA<1>")
		)
		(pad "73" smd rect
			(at 0 61.20003 90)
			(size 1.8034 0.508)
			(layers "F.Cu" "F.Mask" "F.Paste")
			(net "PVDDQ_ABC")
		)
		(pad "74" smd rect
			(at 0 62.049914 90)
			(size 1.8034 0.508)
			(layers "F.Cu" "F.Mask" "F.Paste")
			(net "M_B_CLK_DP<0>")
		)
		(pad "75" smd rect
			(at 0 62.900052 90)
			(size 1.8034 0.508)
			(layers "F.Cu" "F.Mask" "F.Paste")
			(net "M_B_CLK_DN<0>")
		)
		(pad "76" smd rect
			(at 0 63.749936 90)
			(size 1.8034 0.508)
			(layers "F.Cu" "F.Mask" "F.Paste")
			(net "PVDDQ_ABC")
		)
		(pad "77" smd rect
			(at 0 64.600074 90)
			(size 1.8034 0.508)
			(layers "F.Cu" "F.Mask" "F.Paste")
			(net "PVTT_ABC")
		)
		(pad "78" smd rect
			(at 0 70.550024 90)
			(size 1.8034 0.508)
			(layers "F.Cu" "F.Mask" "F.Paste")
			(net "FM_DIMM_EVENT_COD_N")
		)
		(pad "79" smd rect
			(at 0 71.399908 90)
			(size 1.8034 0.508)
			(layers "F.Cu" "F.Mask" "F.Paste")
			(net "M_B_MA<0>")
		)
		(pad "80" smd rect
			(at 0 72.250046 90)
			(size 1.8034 0.508)
			(layers "F.Cu" "F.Mask" "F.Paste")
			(net "PVDDQ_ABC")
		)
		(pad "81" smd rect
			(at 0 73.09993 90)
			(size 1.8034 0.508)
			(layers "F.Cu" "F.Mask" "F.Paste")
			(net "M_B_BA<0>")
		)
		(pad "82" smd rect
			(at 0 73.950068 90)
			(size 1.8034 0.508)
			(layers "F.Cu" "F.Mask" "F.Paste")
			(net "M_B_MA<16>")
		)
		(pad "83" smd rect
			(at 0 74.799952 90)
			(size 1.8034 0.508)
			(layers "F.Cu" "F.Mask" "F.Paste")
			(net "PVDDQ_ABC")
		)
		(pad "84" smd rect
			(at 0 75.65009 90)
			(size 1.8034 0.508)
			(layers "F.Cu" "F.Mask" "F.Paste")
			(net "M_B_CS_N<0>")
		)
		(pad "85" smd rect
			(at 0 76.499974 90)
			(size 1.8034 0.508)
			(layers "F.Cu" "F.Mask" "F.Paste")
			(net "PVDDQ_ABC")
		)
		(pad "86" smd rect
			(at 0 77.350112 90)
			(size 1.8034 0.508)
			(layers "F.Cu" "F.Mask" "F.Paste")
			(net "M_B_MA<15>")
		)
		(pad "87" smd rect
			(at 0 78.199996 90)
			(size 1.8034 0.508)
			(layers "F.Cu" "F.Mask" "F.Paste")
			(net "M_B_ODT<0>")
		)
		(pad "88" smd rect
			(at 0 79.04988 90)
			(size 1.8034 0.508)
			(layers "F.Cu" "F.Mask" "F.Paste")
			(net "PVDDQ_ABC")
		)
		(pad "89" smd rect
			(at 0 79.900018 90)
			(size 1.8034 0.508)
			(layers "F.Cu" "F.Mask" "F.Paste")
			(net "M_B_CS_N<1>")
		)
		(pad "90" smd rect
			(at 0 80.749902 90)
			(size 1.8034 0.508)
			(layers "F.Cu" "F.Mask" "F.Paste")
			(net "PVDDQ_ABC")
		)
		(pad "91" smd rect
			(at 0 81.60004 90)
			(size 1.8034 0.508)
			(layers "F.Cu" "F.Mask" "F.Paste")
			(net "M_B_ODT<1>")
		)
		(pad "92" smd rect
			(at 0 82.449924 90)
			(size 1.8034 0.508)
			(layers "F.Cu" "F.Mask" "F.Paste")
			(net "PVDDQ_ABC")
		)
		(pad "93" smd rect
			(at 0 83.300062 90)
			(size 1.8034 0.508)
			(layers "F.Cu" "F.Mask" "F.Paste")
			(net "M_B_CS_N<2>")
		)
		(pad "94" smd rect
			(at 0 84.149946 90)
			(size 1.8034 0.508)
			(layers "F.Cu" "F.Mask" "F.Paste")
			(net "GND")
		)
		(pad "95" smd rect
			(at 0 85.000084 90)
			(size 1.8034 0.508)
			(layers "F.Cu" "F.Mask" "F.Paste")
			(net "M_B_DQ<37>")
		)
		(pad "96" smd rect
			(at 0 85.849968 90)
			(size 1.8034 0.508)
			(layers "F.Cu" "F.Mask" "F.Paste")
			(net "GND")
		)
		(pad "97" smd rect
			(at 0 86.700106 90)
			(size 1.8034 0.508)
			(layers "F.Cu" "F.Mask" "F.Paste")
			(net "M_B_DQ<33>")
		)
		(pad "98" smd rect
			(at 0 87.54999 90)
			(size 1.8034 0.508)
			(layers "F.Cu" "F.Mask" "F.Paste")
			(net "GND")
		)
	)
)
